(kicad_pcb
	(version 20260206)
	(generator "pcbnew")
	(generator_version "10.0")
	(general
		(thickness 1.6)
		(legacy_teardrops no)
	)
	(paper "A4")
	(title_block
		(title "pdpb — Lightning_PDPB_BRD.brd")
		(comment 1 "Lightning (Wiwynn / Facebook NVMe JBOF) / footprints 149-153 of 1140")
	)
	(layers
		(0 "F.Cu" signal "TOP")
		(4 "In1.Cu" signal "L2GND")
		(6 "In2.Cu" signal "L3")
		(8 "In3.Cu" signal "L4VCC")
		(10 "In4.Cu" signal "L5VCC")
		(12 "In5.Cu" signal "L6")
		(14 "In6.Cu" signal "L7GND")
		(2 "B.Cu" signal "BOTTOM")
		(9 "F.Adhes" user "F.Adhesive")
		(11 "B.Adhes" user "B.Adhesive")
		(13 "F.Paste" user "Package Geometry/Pastemask Top")
		(15 "B.Paste" user "Package Geometry/Pastemask Bottom")
		(5 "F.SilkS" user "Ref Des/Silkscreen Top")
		(7 "B.SilkS" user "Ref Des/Silkscreen Bottom")
		(1 "F.Mask" user "Board Geometry/Soldermask Top")
		(3 "B.Mask" user "Board Geometry/Soldermask Bottom")
		(17 "Dwgs.User" user "User.Drawings")
		(19 "Cmts.User" user "User.Comments")
		(21 "Eco1.User" user "User.Eco1")
		(23 "Eco2.User" user "User.Eco2")
		(25 "Edge.Cuts" user "Board Geometry/Outline")
		(27 "Margin" user)
		(31 "F.CrtYd" user "Package Geometry/Place Bound Top")
		(29 "B.CrtYd" user "Package Geometry/Place Bound Bottom")
		(35 "F.Fab" user "Ref Des/Assembly Top")
		(33 "B.Fab" user "Ref Des/Assembly Bottom")
	)
	(footprint ""
		(layer "F.Cu")
		(at 228.499924 -350.099884)
		(property "Reference" "LED1"
			(at 0 0 0)
			(layer "F.SilkS")
			(hide yes)
			(effects
				(font
					(size 1.27 1.27)
				)
			)
		)
		(property "Value" "LED-RB-4-GP"
			(at 5.88899 1.80848 0)
			(unlocked yes)
			(layer "F.Fab")
			(hide yes)
			(effects
				(font
					(size 1.016 1.016)
					(thickness 0.1524)
				)
			)
		)
		(property "Device Type" "LED1613-4PH20"
			(at 5.88899 0.28448 0)
			(unlocked yes)
			(layer "F.Fab")
			(hide yes)
			(effects
				(font
					(size 1.016 1.016)
					(thickness 0.1524)
				)
			)
		)
		(duplicate_pad_numbers_are_jumpers no)
		(fp_line
			(start -1.4478 -0.9652)
			(end 1.4478 -0.9652)
			(stroke
				(width 0.1524)
				(type default)
			)
			(layer "F.SilkS")
		)
		(fp_line
			(start -1.4478 0.9652)
			(end -1.4478 -0.9652)
			(stroke
				(width 0.1524)
				(type default)
			)
			(layer "F.SilkS")
		)
		(fp_line
			(start -1.4478 0.9652)
			(end -1.4478 -0.9652)
			(stroke
				(width 0.508)
				(type default)
			)
			(layer "F.SilkS")
		)
		(fp_line
			(start 1.4478 -0.9652)
			(end 1.4478 0.9652)
			(stroke
				(width 0.1524)
				(type default)
			)
			(layer "F.SilkS")
		)
		(fp_line
			(start 1.4478 0.9652)
			(end -1.4478 0.9652)
			(stroke
				(width 0.1524)
				(type default)
			)
			(layer "F.SilkS")
		)
		(fp_rect
			(start -0.8001 0.6477)
			(end 0.8001 -0.6477)
			(stroke
				(width 0)
				(type default)
			)
			(fill no)
			(layer "F.CrtYd")
		)
		(fp_poly
			(pts
				(xy -1.7018 1.2192) (xy -1.7018 -0.06223) (xy -0.8001 -0.06223) (xy -0.8001 0.6477) (xy 0.8001 0.6477)
				(xy 0.8001 -0.6477) (xy -0.8001 -0.6477) (xy -0.8001 -0.0635) (xy -1.7018 -0.0635) (xy -1.7018 -1.2192)
				(xy 1.7018 -1.2192) (xy 1.7018 1.2192)
			)
			(stroke
				(width 0)
				(type default)
			)
			(fill no)
			(layer "F.CrtYd")
		)
		(fp_rect
			(start -1.7018 1.2192)
			(end 1.7018 -1.2192)
			(stroke
				(width 0)
				(type default)
			)
			(fill no)
			(layer "F.Fab")
		)
		(pad "1" smd rect
			(at -0.73025 0.4064)
			(size 0.9144 0.6096)
			(layers "F.Cu" "F.Mask" "F.Paste")
			(net "SSD_ACT_DR1_MOS_N")
		)
		(pad "2" smd rect
			(at -0.73025 -0.4064)
			(size 0.9144 0.6096)
			(layers "F.Cu" "F.Mask" "F.Paste")
			(net "ATTN_LED_DR1_MOS_N")
		)
		(pad "3" smd rect
			(at 0.73025 -0.4064)
			(size 0.9144 0.6096)
			(layers "F.Cu" "F.Mask" "F.Paste")
			(net "DRV_ATTN_1")
		)
		(pad "4" smd rect
			(at 0.73025 0.4064)
			(size 0.9144 0.6096)
			(layers "F.Cu" "F.Mask" "F.Paste")
			(net "DRV_ACT_1")
		)
	)
	(footprint ""
		(layer "F.Cu")
		(at 76.2 -148.717)
		(property "Reference" "EU16"
			(at 0 0 0)
			(layer "F.SilkS")
			(hide yes)
			(effects
				(font
					(size 1.27 1.27)
				)
			)
		)
		(property "Value" "PCA9547BS-GP"
			(at 4.064 -5.5372 0)
			(unlocked yes)
			(layer "F.Fab")
			(hide yes)
			(effects
				(font
					(size 1.016 1.016)
					(thickness 0.1524)
				)
			)
		)
		(property "Device Type" "QFN24-G2D25H40"
			(at 4.064 -7.0612 0)
			(unlocked yes)
			(layer "F.Fab")
			(hide yes)
			(effects
				(font
					(size 1.016 1.016)
					(thickness 0.1524)
				)
			)
		)
		(duplicate_pad_numbers_are_jumpers no)
		(fp_line
			(start -3.5306 0.254)
			(end -2.7686 0.254)
			(stroke
				(width 0.1524)
				(type default)
			)
			(layer "F.SilkS")
		)
		(fp_line
			(start -3.0226 -3.0226)
			(end -1.7526 -3.0226)
			(stroke
				(width 0.1524)
				(type default)
			)
			(layer "F.SilkS")
		)
		(fp_line
			(start -3.0226 -1.7526)
			(end -3.0226 -3.0226)
			(stroke
				(width 0.1524)
				(type default)
			)
			(layer "F.SilkS")
		)
		(fp_line
			(start -3.0226 1.7526)
			(end -3.0226 3.0226)
			(stroke
				(width 0.1524)
				(type default)
			)
			(layer "F.SilkS")
		)
		(fp_line
			(start -3.0226 3.0226)
			(end -1.7526 3.0226)
			(stroke
				(width 0.1524)
				(type default)
			)
			(layer "F.SilkS")
		)
		(fp_line
			(start -0.7366 -2.794)
			(end -0.7366 -3.302)
			(stroke
				(width 0.1524)
				(type default)
			)
			(layer "F.SilkS")
		)
		(fp_line
			(start -0.254 3.302)
			(end -0.254 2.794)
			(stroke
				(width 0.1524)
				(type default)
			)
			(layer "F.SilkS")
		)
		(fp_line
			(start 1.7526 3.0226)
			(end 3.0226 3.0226)
			(stroke
				(width 0.1524)
				(type default)
			)
			(layer "F.SilkS")
		)
		(fp_line
			(start 2.8194 0.762)
			(end 3.5814 0.762)
			(stroke
				(width 0.1524)
				(type default)
			)
			(layer "F.SilkS")
		)
		(fp_line
			(start 3.0226 3.0226)
			(end 3.0226 1.7526)
			(stroke
				(width 0.1524)
				(type default)
			)
			(layer "F.SilkS")
		)
		(fp_poly
			(pts
				(xy 1.7526 -3.0226) (xy 3.0226 -1.7526) (xy 3.0226 -3.0226)
			)
			(stroke
				(width 0)
				(type default)
			)
			(fill yes)
			(layer "F.SilkS")
		)
		(fp_rect
			(start -2.0066 2.0066)
			(end 2.0066 -2.0066)
			(stroke
				(width 0)
				(type default)
			)
			(fill no)
			(layer "F.CrtYd")
		)
		(fp_poly
			(pts
				(xy -2.0066 -2.0066) (xy -2.0066 -3.0226) (xy -3.0226 -3.0226) (xy -3.0226 3.0226) (xy 3.0226 3.0226)
				(xy 3.0226 -3.0226) (xy -2.00152 -3.0226) (xy -2.00152 -2.0066) (xy 2.0066 -2.0066) (xy 2.0066 2.0066)
				(xy -2.0066 2.0066)
			)
			(stroke
				(width 0)
				(type default)
			)
			(fill no)
			(layer "F.CrtYd")
		)
		(fp_rect
			(start -3.0226 3.0226)
			(end 3.0226 -3.0226)
			(stroke
				(width 0)
				(type default)
			)
			(fill no)
			(layer "F.Fab")
		)
		(pad "1" smd rect
			(at 1.249934 -2.0574)
			(size 0.3048 0.9144)
			(layers "F.Cu" "F.Mask" "F.Paste")
			(net "SDA_DR3")
		)
		(pad "2" smd rect
			(at 0.750062 -1.9812)
			(size 0.3048 1.0668)
			(layers "F.Cu" "F.Mask" "F.Paste")
			(net "SCL_DR3")
		)
		(pad "3" smd rect
			(at 0.249936 -1.9812)
			(size 0.3048 1.0668)
			(layers "F.Cu" "F.Mask" "F.Paste")
			(net "SDA_DR4")
		)
		(pad "4" smd rect
			(at -0.249936 -1.9812)
			(size 0.3048 1.0668)
			(layers "F.Cu" "F.Mask" "F.Paste")
			(net "SCL_DR4")
		)
		(pad "5" smd rect
			(at -0.750062 -1.9812)
			(size 0.3048 1.0668)
			(layers "F.Cu" "F.Mask" "F.Paste")
			(net "SDA_DR12")
		)
		(pad "6" smd rect
			(at -1.249934 -2.0574)
			(size 0.3048 0.9144)
			(layers "F.Cu" "F.Mask" "F.Paste")
			(net "SCL_DR12")
		)
		(pad "7" smd rect
			(at -2.0574 -1.249934)
			(size 0.9144 0.3048)
			(layers "F.Cu" "F.Mask" "F.Paste")
			(net "SDA_DR8")
		)
		(pad "8" smd rect
			(at -1.9812 -0.750062)
			(size 1.0668 0.3048)
			(layers "F.Cu" "F.Mask" "F.Paste")
			(net "SCL_DR8")
		)
		(pad "9" smd rect
			(at -1.9812 -0.249936)
			(size 1.0668 0.3048)
			(layers "F.Cu" "F.Mask" "F.Paste")
			(net "GND")
		)
		(pad "10" smd rect
			(at -1.9812 0.249936)
			(size 1.0668 0.3048)
			(layers "F.Cu" "F.Mask" "F.Paste")
			(net "SDA_DR13")
		)
		(pad "11" smd rect
			(at -1.9812 0.750062)
			(size 1.0668 0.3048)
			(layers "F.Cu" "F.Mask" "F.Paste")
			(net "SCL_DR13")
		)
		(pad "12" smd rect
			(at -2.0574 1.249934)
			(size 0.9144 0.3048)
			(layers "F.Cu" "F.Mask" "F.Paste")
			(net "SDA_DR9")
		)
		(pad "13" smd rect
			(at -1.249934 2.0574)
			(size 0.3048 0.9144)
			(layers "F.Cu" "F.Mask" "F.Paste")
			(net "SCL_DR9")
		)
		(pad "14" smd rect
			(at -0.750062 1.9812)
			(size 0.3048 1.0668)
			(layers "F.Cu" "F.Mask" "F.Paste")
			(net "SDA_DR14")
		)
		(pad "15" smd rect
			(at -0.249936 1.9812)
			(size 0.3048 1.0668)
			(layers "F.Cu" "F.Mask" "F.Paste")
			(net "SCL_DR14")
		)
		(pad "16" smd rect
			(at 0.249936 1.9812)
			(size 0.3048 1.0668)
			(layers "F.Cu" "F.Mask" "F.Paste")
			(net "Net_419")
		)
		(pad "17" smd rect
			(at 0.750062 1.9812)
			(size 0.3048 1.0668)
			(layers "F.Cu" "F.Mask" "F.Paste")
			(net "Net_418")
		)
		(pad "18" smd rect
			(at 1.249934 2.0574)
			(size 0.3048 0.9144)
			(layers "F.Cu" "F.Mask" "F.Paste")
			(net "I2C_SW_EU16_ADDRESS_A2")
		)
		(pad "19" smd rect
			(at 2.0574 1.249934)
			(size 0.9144 0.3048)
			(layers "F.Cu" "F.Mask" "F.Paste")
			(net "I2C8_SCL_R_SW_EU16")
		)
		(pad "20" smd rect
			(at 1.9812 0.750062)
			(size 1.0668 0.3048)
			(layers "F.Cu" "F.Mask" "F.Paste")
			(net "I2C8_SDA_R_SW_EU16")
		)
		(pad "21" smd rect
			(at 1.9812 0.249936)
			(size 1.0668 0.3048)
			(layers "F.Cu" "F.Mask" "F.Paste")
			(net "P3V3")
		)
		(pad "22" smd rect
			(at 1.9812 -0.249936)
			(size 1.0668 0.3048)
			(layers "F.Cu" "F.Mask" "F.Paste")
			(net "I2C_SW_EU16_ADDRESS_A0")
		)
		(pad "23" smd rect
			(at 1.9812 -0.750062)
			(size 1.0668 0.3048)
			(layers "F.Cu" "F.Mask" "F.Paste")
			(net "I2C_SW_EU16_ADDRESS_A1")
		)
		(pad "24" smd rect
			(at 2.0574 -1.249934)
			(size 0.9144 0.3048)
			(layers "F.Cu" "F.Mask" "F.Paste")
			(net "I2C_MUX_RESET_R_EU16")
		)
		(pad "25" smd rect
			(at 0 0)
			(size 2.2606 2.2606)
			(layers "F.Cu" "F.Mask" "F.Paste")
			(net "GND")
		)
	)
	(footprint ""
		(layer "F.Cu")
		(at 24.003 -51.054 -90)
		(property "Reference" "R9906"
			(at 0 0 270)
			(layer "F.SilkS")
			(hide yes)
			(effects
				(font
					(size 1.27 1.27)
				)
			)
		)
		(property "Value" "1K82R2F-1-GP"
			(at 0.064008 -3.993896 270)
			(unlocked yes)
			(layer "F.Fab")
			(hide yes)
			(effects
				(font
					(size 1.016 1.016)
					(thickness 0.1524)
				)
			)
		)
		(property "Device Type" "R402H16"
			(at 0.064008 -5.517896 270)
			(unlocked yes)
			(layer "F.Fab")
			(hide yes)
			(effects
				(font
					(size 1.016 1.016)
					(thickness 0.1524)
				)
			)
		)
		(duplicate_pad_numbers_are_jumpers no)
		(fp_line
			(start -0.508 -0.9398)
			(end -0.508 0.9398)
			(stroke
				(width 0.1524)
				(type default)
			)
			(layer "F.SilkS")
		)
		(fp_line
			(start 0.508 -0.9398)
			(end -0.508 -0.9398)
			(stroke
				(width 0.1524)
				(type default)
			)
			(layer "F.SilkS")
		)
		(fp_rect
			(start -0.508 0.9398)
			(end 0.508 -0.9398)
			(stroke
				(width 0)
				(type default)
			)
			(fill no)
			(layer "F.CrtYd")
		)
		(fp_rect
			(start -0.508 0.9398)
			(end 0.508 -0.9398)
			(stroke
				(width 0)
				(type default)
			)
			(fill no)
			(layer "F.Fab")
		)
		(pad "1" smd custom
			(at 0 -0.4445 270)
			(size 0.1397 0.1397)
			(layers "F.Cu" "F.Mask" "F.Paste")
			(net "P12V")
			(options
				(clearance outline)
				(anchor circle)
			)
			(primitives
				(gr_poly
					(pts
						(arc
							(start -0.1778 -0.2794)
							(mid -0.249642 -0.249642)
							(end -0.2794 -0.1778)
						)
						(arc
							(start -0.2794 0.1778)
							(mid -0.249642 0.249642)
							(end -0.1778 0.2794)
						)
						(arc
							(start 0.1778 0.2794)
							(mid 0.249642 0.249642)
							(end 0.2794 0.1778)
						)
						(arc
							(start 0.2794 -0.1778)
							(mid 0.249642 -0.249642)
							(end 0.1778 -0.2794)
						)
					)
					(width 0)
					(fill yes)
				)
			)
		)
		(pad "2" smd custom
			(at 0 0.4445 270)
			(size 0.1397 0.1397)
			(layers "F.Cu" "F.Mask" "F.Paste")
			(net "DRV_ACT_14")
			(options
				(clearance outline)
				(anchor circle)
			)
			(primitives
				(gr_poly
					(pts
						(arc
							(start -0.1778 -0.2794)
							(mid -0.249642 -0.249642)
							(end -0.2794 -0.1778)
						)
						(arc
							(start -0.2794 0.1778)
							(mid -0.249642 0.249642)
							(end -0.1778 0.2794)
						)
						(arc
							(start 0.1778 0.2794)
							(mid 0.249642 0.249642)
							(end 0.2794 0.1778)
						)
						(arc
							(start 0.2794 -0.1778)
							(mid 0.249642 -0.249642)
							(end 0.1778 -0.2794)
						)
					)
					(width 0)
					(fill yes)
				)
			)
		)
	)
	(footprint ""
		(layer "F.Cu")
		(at 219.964 -400.685 180)
		(property "Reference" "PC1237"
			(at 0 0 180)
			(layer "F.SilkS")
			(hide yes)
			(effects
				(font
					(size 1.27 1.27)
				)
			)
		)
		(property "Value" "SCD1U50V3KX-GP"
			(at 0 -2.8194 180)
			(unlocked yes)
			(layer "F.Fab")
			(hide yes)
			(effects
				(font
					(size 1.016 1.016)
					(thickness 0.1524)
				)
			)
		)
		(property "Device Type" "C603H36"
			(at 0 -4.3434 180)
			(unlocked yes)
			(layer "F.Fab")
			(hide yes)
			(effects
				(font
					(size 1.016 1.016)
					(thickness 0.1524)
				)
			)
		)
		(duplicate_pad_numbers_are_jumpers no)
		(fp_line
			(start 0.508 0)
			(end -0.508 0)
			(stroke
				(width 0.2032)
				(type default)
			)
			(layer "F.SilkS")
		)
		(fp_rect
			(start -0.5842 1.3335)
			(end 0.5842 -1.3335)
			(stroke
				(width 0)
				(type default)
			)
			(fill no)
			(layer "F.CrtYd")
		)
		(fp_rect
			(start -0.5842 1.3335)
			(end 0.5842 -1.3335)
			(stroke
				(width 0)
				(type default)
			)
			(fill no)
			(layer "F.Fab")
		)
		(pad "1" smd custom
			(at 0 -0.762 180)
			(size 0.2159 0.2159)
			(layers "F.Cu" "F.Mask" "F.Paste")
			(net "P12V_SSD1")
			(options
				(clearance outline)
				(anchor circle)
			)
			(primitives
				(gr_poly
					(pts
						(arc
							(start -0.3302 -0.4318)
							(mid -0.402042 -0.402042)
							(end -0.4318 -0.3302)
						)
						(arc
							(start -0.4318 0.3302)
							(mid -0.402042 0.402042)
							(end -0.3302 0.4318)
						)
						(arc
							(start 0.3302 0.4318)
							(mid 0.402042 0.402042)
							(end 0.4318 0.3302)
						)
						(arc
							(start 0.4318 -0.3302)
							(mid 0.402042 -0.402042)
							(end 0.3302 -0.4318)
						)
					)
					(width 0)
					(fill yes)
				)
			)
		)
		(pad "2" smd custom
			(at 0 0.762 180)
			(size 0.2159 0.2159)
			(layers "F.Cu" "F.Mask" "F.Paste")
			(net "GND")
			(options
				(clearance outline)
				(anchor circle)
			)
			(primitives
				(gr_poly
					(pts
						(arc
							(start -0.3302 -0.4318)
							(mid -0.402042 -0.402042)
							(end -0.4318 -0.3302)
						)
						(arc
							(start -0.4318 0.3302)
							(mid -0.402042 0.402042)
							(end -0.3302 0.4318)
						)
						(arc
							(start 0.3302 0.4318)
							(mid 0.402042 0.402042)
							(end 0.4318 0.3302)
						)
						(arc
							(start 0.4318 -0.3302)
							(mid 0.402042 -0.402042)
							(end 0.3302 -0.4318)
						)
					)
					(width 0)
					(fill yes)
				)
			)
		)
	)
	(footprint ""
		(layer "F.Cu")
		(at 97.028 -290.195 -90)
		(property "Reference" "R9402"
			(at 0 0 270)
			(layer "F.SilkS")
			(hide yes)
			(effects
				(font
					(size 1.27 1.27)
				)
			)
		)
		(property "Value" "4K7R2J-2-GP"
			(at 0.064008 -3.993896 270)
			(unlocked yes)
			(layer "F.Fab")
			(hide yes)
			(effects
				(font
					(size 1.016 1.016)
					(thickness 0.1524)
				)
			)
		)
		(property "Device Type" "R402H16"
			(at 0.064008 -5.517896 270)
			(unlocked yes)
			(layer "F.Fab")
			(hide yes)
			(effects
				(font
					(size 1.016 1.016)
					(thickness 0.1524)
				)
			)
		)
		(duplicate_pad_numbers_are_jumpers no)
		(fp_line
			(start -0.508 -0.9398)
			(end -0.508 0.9398)
			(stroke
				(width 0.1524)
				(type default)
			)
			(layer "F.SilkS")
		)
		(fp_line
			(start 0.508 -0.9398)
			(end -0.508 -0.9398)
			(stroke
				(width 0.1524)
				(type default)
			)
			(layer "F.SilkS")
		)
		(fp_rect
			(start -0.508 0.9398)
			(end 0.508 -0.9398)
			(stroke
				(width 0)
				(type default)
			)
			(fill no)
			(layer "F.CrtYd")
		)
		(fp_rect
			(start -0.508 0.9398)
			(end 0.508 -0.9398)
			(stroke
				(width 0)
				(type default)
			)
			(fill no)
			(layer "F.Fab")
		)
		(pad "1" smd custom
			(at 0 -0.4445 270)
			(size 0.1397 0.1397)
			(layers "F.Cu" "F.Mask" "F.Paste")
			(net "P3V3")
			(options
				(clearance outline)
				(anchor circle)
			)
			(primitives
				(gr_poly
					(pts
						(arc
							(start -0.1778 -0.2794)
							(mid -0.249642 -0.249642)
							(end -0.2794 -0.1778)
						)
						(arc
							(start -0.2794 0.1778)
							(mid -0.249642 0.249642)
							(end -0.1778 0.2794)
						)
						(arc
							(start 0.1778 0.2794)
							(mid 0.249642 0.249642)
							(end 0.2794 0.1778)
						)
						(arc
							(start 0.2794 -0.1778)
							(mid 0.249642 -0.249642)
							(end 0.1778 -0.2794)
						)
					)
					(width 0)
					(fill yes)
				)
			)
		)
		(pad "2" smd custom
			(at 0 0.4445 270)
			(size 0.1397 0.1397)
			(layers "F.Cu" "F.Mask" "F.Paste")
			(net "SSD_PRSNT_NET2")
			(options
				(clearance outline)
				(anchor circle)
			)
			(primitives
				(gr_poly
					(pts
						(arc
							(start -0.1778 -0.2794)
							(mid -0.249642 -0.249642)
							(end -0.2794 -0.1778)
						)
						(arc
							(start -0.2794 0.1778)
							(mid -0.249642 0.249642)
							(end -0.1778 0.2794)
						)
						(arc
							(start 0.1778 0.2794)
							(mid 0.249642 0.249642)
							(end 0.2794 0.1778)
						)
						(arc
							(start 0.2794 -0.1778)
							(mid 0.249642 -0.249642)
							(end 0.1778 -0.2794)
						)
					)
					(width 0)
					(fill yes)
				)
			)
		)
	)
)
